(kicad_pcb
	(version 20260206)
	(generator "pcbnew")
	(generator_version "10.0")
	(general
		(thickness 1.21888)
		(legacy_teardrops no)
	)
	(paper "A4")
	(title_block
		(title "timecard-v9 — TimeCard-DC-V9_EXP.PcbDoc")
		(comment 1 "Time Appliance Project (Time Card) / footprints 25-26 of 402")
	)
	(layers
		(0 "F.Cu" signal "TOP")
		(4 "In1.Cu" signal "SGND")
		(6 "In2.Cu" signal "IN1")
		(8 "In3.Cu" signal "IN2")
		(10 "In4.Cu" signal "SGND1")
		(2 "B.Cu" signal "BOTTOM")
		(9 "F.Adhes" user "F.Adhesive")
		(11 "B.Adhes" user "B.Adhesive")
		(13 "F.Paste" user "Top Paste")
		(15 "B.Paste" user "Bottom Paste")
		(5 "F.SilkS" user "Top Overlay")
		(7 "B.SilkS" user "Bottom Overlay")
		(1 "F.Mask" user "Top Solder")
		(3 "B.Mask" user "Bottom Solder")
		(17 "Dwgs.User" user "User.Drawings")
		(19 "Cmts.User" user "User.Comments")
		(21 "Eco1.User" user "User.Eco1")
		(23 "Eco2.User" user "User.Eco2")
		(25 "Edge.Cuts" user)
		(27 "Margin" user)
		(31 "F.CrtYd" user "Top Courtyard")
		(29 "B.CrtYd" user "Bottom Courtyard")
		(35 "F.Fab" user "Top Component Center")
		(33 "B.Fab" user "Bottom Component Center")
	)
	(footprint "MUN12AD06-SM:MUN12AD06-SM_CYN"
		(layer "F.Cu")
		(at 97.6632 58.6162 -90)
		(property "Reference" "U1"
			(at 2.003195 -4.731469 270)
			(unlocked yes)
			(layer "F.SilkS")
			(effects
				(font
					(size 0.762 0.762)
					(thickness 0.2032)
				)
			)
		)
		(property "Value" "MUN12AD06-SM"
			(at 5.027635 -0.734819 270)
			(unlocked yes)
			(layer "F.SilkS")
			(hide yes)
			(effects
				(font
					(size 0.762 0.762)
					(thickness 0.2032)
				)
			)
		)
		(sheetname "03-POWER")
		(sheetfile "03-POWER.kicad_sch")
		(duplicate_pad_numbers_are_jumpers no)
		(fp_line
			(start -3.1242 3.1242)
			(end -3.1242 2.00688)
			(stroke
				(width 0.1524)
				(type solid)
			)
			(layer "F.SilkS")
		)
		(fp_line
			(start -2.00688 3.1242)
			(end -3.1242 3.1242)
			(stroke
				(width 0.1524)
				(type solid)
			)
			(layer "F.SilkS")
		)
		(fp_line
			(start 3.1242 3.1242)
			(end 2.00688 3.1242)
			(stroke
				(width 0.1524)
				(type solid)
			)
			(layer "F.SilkS")
		)
		(fp_line
			(start 3.1242 3.1242)
			(end 3.1242 2.00688)
			(stroke
				(width 0.1524)
				(type solid)
			)
			(layer "F.SilkS")
		)
		(fp_line
			(start -3.1242 -2.00688)
			(end -3.1242 -3.1242)
			(stroke
				(width 0.1524)
				(type solid)
			)
			(layer "F.SilkS")
		)
		(fp_line
			(start 3.1242 -2.00688)
			(end 3.1242 -3.1242)
			(stroke
				(width 0.1524)
				(type solid)
			)
			(layer "F.SilkS")
		)
		(fp_line
			(start -2.00688 -3.1242)
			(end -3.1242 -3.1242)
			(stroke
				(width 0.1524)
				(type solid)
			)
			(layer "F.SilkS")
		)
		(fp_line
			(start 3.1242 -3.1242)
			(end 2.00688 -3.1242)
			(stroke
				(width 0.1524)
				(type solid)
			)
			(layer "F.SilkS")
		)
		(fp_poly
			(pts
				(xy 1.7905 3.1496) (xy 1.4095 3.1496) (xy 1.4095 3.4036) (xy 1.7905 3.4036)
			)
			(stroke
				(width 0)
				(type default)
			)
			(fill yes)
			(layer "F.SilkS")
		)
		(fp_poly
			(pts
				(xy -1.4095 -3.1496) (xy -1.7905 -3.1496) (xy -1.7905 -3.4036) (xy -1.4095 -3.4036)
			)
			(stroke
				(width 0)
				(type default)
			)
			(fill yes)
			(layer "F.SilkS")
		)
		(fp_text user "*"
			(at 1.2 -1.344425 270)
			(unlocked yes)
			(layer "F.SilkS")
			(effects
				(font
					(size 1.27 1.27)
					(thickness 0.0762)
				)
				(justify left bottom)
			)
		)
		(pad "1" smd rect
			(at -2.6416 -1.6 180)
			(size 0.3302 0.508)
			(layers "F.Cu" "F.Mask" "F.Paste")
			(net "+12V")
			(solder_mask_margin 0)
			(solder_paste_margin 0)
		)
		(pad "2" smd rect
			(at -2.6416 -0.8 180)
			(size 0.3302 0.508)
			(layers "F.Cu" "F.Mask" "F.Paste")
			(net "P5V_MUN_PHASE")
			(solder_mask_margin 0)
			(solder_paste_margin 0)
		)
		(pad "3" smd rect
			(at -2.6416 0 180)
			(size 0.3302 0.508)
			(layers "F.Cu" "F.Mask" "F.Paste")
			(net "P5V_MUN_PHASE")
			(solder_mask_margin 0)
			(solder_paste_margin 0)
		)
		(pad "4" smd rect
			(at -2.6416 0.8 180)
			(size 0.3302 0.508)
			(layers "F.Cu" "F.Mask" "F.Paste")
			(net "P5V_MUN_PHASE")
			(solder_mask_margin 0)
			(solder_paste_margin 0)
		)
		(pad "5" smd rect
			(at -2.6416 1.6 180)
			(size 0.3302 0.508)
			(layers "F.Cu" "F.Mask" "F.Paste")
			(net "GND")
			(solder_mask_margin 0)
			(solder_paste_margin 0)
		)
		(pad "6" smd rect
			(at -1.6 2.6416 90)
			(size 0.3302 0.508)
			(layers "F.Cu" "F.Mask" "F.Paste")
			(net "GND")
			(solder_mask_margin 0)
			(solder_paste_margin 0)
		)
		(pad "7" smd rect
			(at -0.8 2.6416 90)
			(size 0.3302 0.508)
			(layers "F.Cu" "F.Mask" "F.Paste")
			(net "GND")
			(solder_mask_margin 0)
			(solder_paste_margin 0)
		)
		(pad "8" smd rect
			(at 0 2.6416 90)
			(size 0.3302 0.508)
			(layers "F.Cu" "F.Mask" "F.Paste")
			(net "NetR4_2")
			(solder_mask_margin 0)
			(solder_paste_margin 0)
		)
		(pad "9" smd rect
			(at 0.8 2.6416 90)
			(size 0.3302 0.508)
			(layers "F.Cu" "F.Mask" "F.Paste")
			(net "NetR5_1")
			(solder_mask_margin 0)
			(solder_paste_margin 0)
		)
		(pad "10" smd rect
			(at 1.6 2.6416 90)
			(size 0.3302 0.508)
			(layers "F.Cu" "F.Mask" "F.Paste")
			(net "P5V_SENSE")
			(solder_mask_margin 0)
			(solder_paste_margin 0)
		)
		(pad "11" smd rect
			(at 2.6416 1.6 180)
			(size 0.3302 0.508)
			(layers "F.Cu" "F.Mask" "F.Paste")
			(net "P5V_SENSE")
			(solder_mask_margin 0)
			(solder_paste_margin 0)
		)
		(pad "12" smd rect
			(at 2.6416 0.8 180)
			(size 0.3302 0.508)
			(layers "F.Cu" "F.Mask" "F.Paste")
			(net "P5V_SENSE")
			(solder_mask_margin 0)
			(solder_paste_margin 0)
		)
		(pad "13" smd rect
			(at 2.6416 0 180)
			(size 0.3302 0.508)
			(layers "F.Cu" "F.Mask" "F.Paste")
			(net "P5V_SENSE")
			(solder_mask_margin 0)
			(solder_paste_margin 0)
		)
		(pad "14" smd rect
			(at 2.6416 -0.8 180)
			(size 0.3302 0.508)
			(layers "F.Cu" "F.Mask" "F.Paste")
			(net "P5V_SENSE")
			(solder_mask_margin 0)
			(solder_paste_margin 0)
		)
		(pad "15" smd rect
			(at 2.6416 -1.6 180)
			(size 0.3302 0.508)
			(layers "F.Cu" "F.Mask" "F.Paste")
			(net "GND")
			(solder_mask_margin 0)
			(solder_paste_margin 0)
		)
		(pad "16" smd rect
			(at 1.6 -2.6416 90)
			(size 0.3302 0.508)
			(layers "F.Cu" "F.Mask" "F.Paste")
			(net "P5V_MUN_FB")
			(solder_mask_margin 0)
			(solder_paste_margin 0)
		)
		(pad "17" smd rect
			(at 0.8 -2.6416 90)
			(size 0.3302 0.508)
			(layers "F.Cu" "F.Mask" "F.Paste")
			(net "P5V_MUN_VCC")
			(solder_mask_margin 0)
			(solder_paste_margin 0)
		)
		(pad "18" smd rect
			(at 0 -2.6416 90)
			(size 0.3302 0.508)
			(layers "F.Cu" "F.Mask" "F.Paste")
			(solder_mask_margin 0)
			(solder_paste_margin 0)
		)
		(pad "19" smd rect
			(at -0.8 -2.6416 90)
			(size 0.3302 0.508)
			(layers "F.Cu" "F.Mask" "F.Paste")
			(net "+12V")
			(solder_mask_margin 0)
			(solder_paste_margin 0)
		)
		(pad "20" smd rect
			(at -1.6 -2.6416 90)
			(size 0.3302 0.508)
			(layers "F.Cu" "F.Mask" "F.Paste")
			(net "+12V")
			(solder_mask_margin 0)
			(solder_paste_margin 0)
		)
		(pad "21" smd rect
			(at -0.91 -1.67 270)
			(size 1.8796 0.3556)
			(layers "F.Cu" "F.Mask" "F.Paste")
			(net "+12V")
			(solder_mask_margin 0)
			(solder_paste_margin 0)
		)
		(pad "22" smd rect
			(at -0.91 -0.86 270)
			(size 1.8796 0.6604)
			(layers "F.Cu" "F.Mask" "F.Paste")
			(net "P5V_MUN_PHASE")
			(solder_mask_margin 0)
			(solder_paste_margin 0)
		)
		(pad "23" smd rect
			(at -0.91 0.8 270)
			(size 1.8796 2.1082)
			(layers "F.Cu" "F.Mask" "F.Paste")
			(net "GND")
			(solder_mask_margin 0)
			(solder_paste_margin 0)
		)
		(pad "24" smd rect
			(at 1.4 0.8 270)
			(size 0.889 2.1082)
			(layers "F.Cu" "F.Mask" "F.Paste")
			(net "P5V_SENSE")
			(solder_mask_margin 0)
			(solder_paste_margin 0)
		)
		(pad "25" smd rect
			(at 1.4 -1.2 270)
			(size 0.889 1.2954)
			(layers "F.Cu" "F.Mask" "F.Paste")
			(net "GND")
			(solder_mask_margin 0)
			(solder_paste_margin 0)
		)
	)
	(footprint "Vault:RESC1005X40X25NL05T05"
		(layer "F.Cu")
		(at 230.2216 113.1162)
		(property "Reference" "R13"
			(at 0.3286 -0.873069 0)
			(unlocked yes)
			(layer "F.SilkS")
			(effects
				(font
					(size 0.762 0.762)
					(thickness 0.2286)
				)
			)
		)
		(property "Value" "27_1%_0402"
			(at -2.884671 3.18659 270)
			(unlocked yes)
			(layer "F.SilkS")
			(hide yes)
			(effects
				(font
					(size 0.762 0.762)
					(thickness 0.2286)
				)
			)
		)
		(sheetname "09-USBUart_PPSMUX_UARTMUX")
		(sheetfile "09-USBUart_PPSMUX_UARTMUX.kicad_sch")
		(duplicate_pad_numbers_are_jumpers no)
		(pad "1" smd rect
			(at -0.45 0 90)
			(size 0.55 0.55)
			(layers "F.Cu" "F.Mask" "F.Paste")
			(net "NetR13_1")
		)
		(pad "2" smd rect
			(at 0.45 0 90)
			(size 0.55 0.55)
			(layers "F.Cu" "F.Mask" "F.Paste")
			(net "FTDI_TX")
		)
	)
)
